# T6G (Grand Teton) — schematic netlist excerpt (pin names and nets, part order shuffled) for the footprints in the layout excerpt that follows; sources: Cadence DE-HDL packaged netlist, KiCad conversion of 04192023_DAF0TMB3IC0_F0TG_MB_C_brd_V02_OCP.brd

R2996  Q_RES  33.2 1% CHIP  pkg 0402LF  page 151 : A = SMB_PMBUS_3V3AUX_SDA ; B = SMB_SML1_PMBUS_HSC_SDA
C459  Q_CAP  1UF 4V 20% X6S  pkg 0201  page 356 : A = P0V9_CPU1_RT3_2A ; B = GND
PC517_1  Q_CAP  22UF 16V 20% X6S  pkg C0805  page 225 : A = SW_P12V_AUX_PVDD11_S3_P1_FLT ; B = GND

(kicad_pcb
	(version 20260206)
	(generator "pcbnew")
	(generator_version "10.0")
	(general
		(thickness 1.6)
		(legacy_teardrops no)
	)
	(paper "A4")
	(title_block
		(title "04192023_DAF0TMB3IC0_F0TG_MB_C_brd_V02_OCP.brd")
		(comment 1 "Grand Teton / footprints 7125-7127 of 8354")
	)
	(layers
		(0 "F.Cu" signal "TOP")
		(4 "In1.Cu" signal "GND")
		(6 "In2.Cu" signal "IN1")
		(8 "In3.Cu" signal "GND1")
		(10 "In4.Cu" signal "IN2")
		(12 "In5.Cu" signal "GND2")
		(14 "In6.Cu" signal "IN3")
		(16 "In7.Cu" signal "GND3")
		(18 "In8.Cu" signal "VCC")
		(20 "In9.Cu" signal "VCC1")
		(22 "In10.Cu" signal "GND4")
		(24 "In11.Cu" signal "IN4")
		(26 "In12.Cu" signal "GND5")
		(28 "In13.Cu" signal "IN5")
		(30 "In14.Cu" signal "GND6")
		(32 "In15.Cu" signal "IN6")
		(34 "In16.Cu" signal "GND7")
		(2 "B.Cu" signal "BOTTOM")
		(9 "F.Adhes" user "F.Adhesive")
		(11 "B.Adhes" user "B.Adhesive")
		(13 "F.Paste" user "Package Geometry/Pastemask Top")
		(15 "B.Paste" user "Package Geometry/Pastemask Bottom")
		(5 "F.SilkS" user "Ref Des/Silkscreen Top")
		(7 "B.SilkS" user "Ref Des/Silkscreen Bottom")
		(1 "F.Mask" user "Board Geometry/Soldermask Top")
		(3 "B.Mask" user "Board Geometry/Soldermask Bottom")
		(17 "Dwgs.User" user "User.Drawings")
		(19 "Cmts.User" user "User.Comments")
		(21 "Eco1.User" user "User.Eco1")
		(23 "Eco2.User" user "User.Eco2")
		(25 "Edge.Cuts" user "Board Geometry/Outline")
		(27 "Margin" user)
		(31 "F.CrtYd" user "Package Geometry/Place Bound Top")
		(29 "B.CrtYd" user "Package Geometry/Place Bound Bottom")
		(35 "F.Fab" user "Ref Des/Assembly Top")
		(33 "B.Fab" user "Ref Des/Assembly Bottom")
	)
	(footprint ""
		(layer "B.Cu")
		(at 164.957506 -16.44523 180)
		(property "Reference" "R2996"
			(at 0 0 0)
			(layer "B.SilkS")
			(hide yes)
			(effects
				(font
					(size 1.27 1.27)
				)
				(justify mirror)
			)
		)
		(property "Value" ""
			(at 0 0 0)
			(layer "B.Fab")
			(effects
				(font
					(size 1.27 1.27)
				)
				(justify mirror)
			)
		)
		(duplicate_pad_numbers_are_jumpers no)
		(fp_line
			(start 0.7874 0.4064)
			(end 0.7874 -0.4064)
			(stroke
				(width 0.1524)
				(type default)
			)
			(layer "B.SilkS")
		)
		(fp_line
			(start 0.7874 -0.4064)
			(end -0.7874 -0.4064)
			(stroke
				(width 0.1524)
				(type default)
			)
			(layer "B.SilkS")
		)
		(fp_line
			(start -0.7874 0.4064)
			(end 0.7874 0.4064)
			(stroke
				(width 0.1524)
				(type default)
			)
			(layer "B.SilkS")
		)
		(fp_line
			(start -0.7874 -0.4064)
			(end -0.7874 0.4064)
			(stroke
				(width 0.1524)
				(type default)
			)
			(layer "B.SilkS")
		)
		(fp_line
			(start 0.67945 0.3048)
			(end 0.67945 -0.305054)
			(stroke
				(width 0.1)
				(type default)
			)
			(layer "B.Fab")
		)
		(fp_line
			(start 0.67945 -0.305054)
			(end 0.12065 -0.305054)
			(stroke
				(width 0.1)
				(type default)
			)
			(layer "B.Fab")
		)
		(fp_line
			(start 0.12065 0.3048)
			(end 0.67945 0.3048)
			(stroke
				(width 0.1)
				(type default)
			)
			(layer "B.Fab")
		)
		(fp_line
			(start 0.12065 0.2794)
			(end 0.12065 0.3048)
			(stroke
				(width 0.1)
				(type default)
			)
			(layer "B.Fab")
		)
		(fp_line
			(start 0.12065 -0.2794)
			(end -0.12065 -0.2794)
			(stroke
				(width 0.1)
				(type default)
			)
			(layer "B.Fab")
		)
		(fp_line
			(start 0.12065 -0.305054)
			(end 0.12065 -0.2794)
			(stroke
				(width 0.1)
				(type default)
			)
			(layer "B.Fab")
		)
		(fp_line
			(start -0.120396 0.3048)
			(end -0.120396 0.2794)
			(stroke
				(width 0.1)
				(type default)
			)
			(layer "B.Fab")
		)
		(fp_line
			(start -0.120396 0.2794)
			(end 0.12065 0.2794)
			(stroke
				(width 0.1)
				(type default)
			)
			(layer "B.Fab")
		)
		(fp_line
			(start -0.12065 -0.2794)
			(end -0.12065 -0.3048)
			(stroke
				(width 0.1)
				(type default)
			)
			(layer "B.Fab")
		)
		(fp_line
			(start -0.12065 -0.3048)
			(end -0.67945 -0.3048)
			(stroke
				(width 0.1)
				(type default)
			)
			(layer "B.Fab")
		)
		(fp_line
			(start -0.67945 0.3048)
			(end -0.120396 0.3048)
			(stroke
				(width 0.1)
				(type default)
			)
			(layer "B.Fab")
		)
		(fp_line
			(start -0.67945 -0.3048)
			(end -0.67945 0.3048)
			(stroke
				(width 0.1)
				(type default)
			)
			(layer "B.Fab")
		)
		(pad "1" smd circle
			(at 0.40005 0)
			(size 0 0)
			(layers "B.Cu" "B.Mask" "B.Paste")
			(net "SMB_PMBUS_3V3AUX_SDA")
		)
		(pad "2" smd circle
			(at -0.40005 0)
			(size 0 0)
			(layers "B.Cu" "B.Mask" "B.Paste")
			(net "SMB_SML1_PMBUS_HSC_SDA")
		)
	)
	(footprint ""
		(layer "B.Cu")
		(at 114.272822 -385.50088 -90)
		(property "Reference" "C459"
			(at 0 0 90)
			(layer "B.SilkS")
			(hide yes)
			(effects
				(font
					(size 1.27 1.27)
				)
				(justify mirror)
			)
		)
		(property "Value" ""
			(at 0 0 90)
			(layer "B.Fab")
			(effects
				(font
					(size 1.27 1.27)
				)
				(justify mirror)
			)
		)
		(duplicate_pad_numbers_are_jumpers no)
		(fp_line
			(start -0.299974 0.150114)
			(end 0.299974 0.150114)
			(stroke
				(width 0.1)
				(type default)
			)
			(layer "B.Fab")
		)
		(fp_line
			(start 0.299974 0.150114)
			(end 0.299974 -0.150114)
			(stroke
				(width 0.1)
				(type default)
			)
			(layer "B.Fab")
		)
		(fp_line
			(start -0.299974 -0.150114)
			(end -0.299974 0.150114)
			(stroke
				(width 0.1)
				(type default)
			)
			(layer "B.Fab")
		)
		(fp_line
			(start 0.299974 -0.150114)
			(end -0.299974 -0.150114)
			(stroke
				(width 0.1)
				(type default)
			)
			(layer "B.Fab")
		)
		(pad "1" smd rect
			(at 0.2667 0 90)
			(size 0.3048 0.381)
			(layers "B.Cu" "B.Mask" "B.Paste")
			(net "P0V9_CPU1_RT3_2A")
		)
		(pad "2" smd rect
			(at -0.2667 0 90)
			(size 0.3048 0.381)
			(layers "B.Cu" "B.Mask" "B.Paste")
			(net "GND")
		)
	)
	(footprint ""
		(layer "B.Cu")
		(at 184.1246 -355.052884 -90)
		(property "Reference" "PC517_1"
			(at 0 0 90)
			(layer "B.SilkS")
			(hide yes)
			(effects
				(font
					(size 1.27 1.27)
				)
				(justify mirror)
			)
		)
		(property "Value" ""
			(at 0 0 90)
			(layer "B.Fab")
			(effects
				(font
					(size 1.27 1.27)
				)
				(justify mirror)
			)
		)
		(duplicate_pad_numbers_are_jumpers no)
		(fp_line
			(start -1.524 0.762)
			(end 1.524 0.762)
			(stroke
				(width 0.1524)
				(type default)
			)
			(layer "B.SilkS")
		)
		(fp_line
			(start 1.524 0.762)
			(end 1.524 -0.762)
			(stroke
				(width 0.1524)
				(type default)
			)
			(layer "B.SilkS")
		)
		(fp_line
			(start -1.524 -0.762)
			(end -1.524 0.762)
			(stroke
				(width 0.1524)
				(type default)
			)
			(layer "B.SilkS")
		)
		(fp_line
			(start 1.524 -0.762)
			(end -1.524 -0.762)
			(stroke
				(width 0.1524)
				(type default)
			)
			(layer "B.SilkS")
		)
		(fp_line
			(start -1.1049 0.724916)
			(end -1.1049 -0.724916)
			(stroke
				(width 0.1)
				(type default)
			)
			(layer "B.Fab")
		)
		(fp_line
			(start 1.1049 0.724916)
			(end -1.1049 0.724916)
			(stroke
				(width 0.1)
				(type default)
			)
			(layer "B.Fab")
		)
		(fp_line
			(start -1.1049 -0.724916)
			(end 1.1049 -0.724916)
			(stroke
				(width 0.1)
				(type default)
			)
			(layer "B.Fab")
		)
		(fp_line
			(start 1.1049 -0.724916)
			(end 1.1049 0.724916)
			(stroke
				(width 0.1)
				(type default)
			)
			(layer "B.Fab")
		)
		(pad "1" smd rect
			(at 0.889 0 270)
			(size 1.016 1.27)
			(layers "B.Cu" "B.Mask" "B.Paste")
			(net "SW_P12V_AUX_PVDD11_S3_P1_FLT")
		)
		(pad "2" smd rect
			(at -0.889 0 270)
			(size 1.016 1.27)
			(layers "B.Cu" "B.Mask" "B.Paste")
			(net "GND")
		)
	)
)
